# BASEBOARD_FAB2 (Tioga Pass) — schematic netlist excerpt (pin names and nets, part order shuffled) for the footprints in the layout excerpt that follows; sources: Cadence DE-HDL packaged netlist, KiCad conversion of Wiwynn_Tioga_Pass_MB.brd

R3R11  RES  10.0K 1% EMPTY  pkg 0402  page 189 : A = FM_JTAG_PLD_EN_DEBUG ; B = GND
R7G31  RES  1.00K 1% CHIP  pkg 0402  page 136 : A = P3V3_STBY ; B = PU_BIOS_RECOVER_BOOT
C6R9  CAPP  470UF 2.5V 20% ALUM  pkg 3018  page 203 : A = PVCCIN_CPU0 ; B = GND

(kicad_pcb
	(version 20260206)
	(generator "pcbnew")
	(generator_version "10.0")
	(general
		(thickness 1.6)
		(legacy_teardrops no)
	)
	(paper "A4")
	(title_block
		(title "Wiwynn_Tioga_Pass_MB.brd")
		(comment 1 "Tioga Pass / footprints 3975-3977 of 4770")
	)
	(layers
		(0 "F.Cu" signal "TOP")
		(4 "In1.Cu" signal "L2GND")
		(6 "In2.Cu" signal "L3")
		(8 "In3.Cu" signal "L4GND")
		(10 "In4.Cu" signal "L5")
		(12 "In5.Cu" signal "L6GND")
		(14 "In6.Cu" signal "L7VCC")
		(16 "In7.Cu" signal "L8VCC")
		(18 "In8.Cu" signal "L9GND")
		(20 "In9.Cu" signal "L10")
		(22 "In10.Cu" signal "L11GND")
		(24 "In11.Cu" signal "L12")
		(26 "In12.Cu" signal "L13GND")
		(2 "B.Cu" signal "BOTTOM")
		(9 "F.Adhes" user "F.Adhesive")
		(11 "B.Adhes" user "B.Adhesive")
		(13 "F.Paste" user "Package Geometry/Pastemask Top")
		(15 "B.Paste" user "Package Geometry/Pastemask Bottom")
		(5 "F.SilkS" user "Ref Des/Silkscreen Top")
		(7 "B.SilkS" user "Ref Des/Silkscreen Bottom")
		(1 "F.Mask" user "Board Geometry/Soldermask Top")
		(3 "B.Mask" user "Board Geometry/Soldermask Bottom")
		(17 "Dwgs.User" user "User.Drawings")
		(19 "Cmts.User" user "User.Comments")
		(21 "Eco1.User" user "User.Eco1")
		(23 "Eco2.User" user "User.Eco2")
		(25 "Edge.Cuts" user "Board Geometry/Outline")
		(27 "Margin" user)
		(31 "F.CrtYd" user "Package Geometry/Place Bound Top")
		(29 "B.CrtYd" user "Package Geometry/Place Bound Bottom")
		(35 "F.Fab" user "Ref Des/Assembly Top")
		(33 "B.Fab" user "Ref Des/Assembly Bottom")
	)
	(footprint ""
		(layer "B.Cu")
		(at 370.29009 -66.300604)
		(property "Reference" "R3R11"
			(at 0 0 0)
			(layer "B.SilkS")
			(hide yes)
			(effects
				(font
					(size 1.27 1.27)
				)
				(justify mirror)
			)
		)
		(property "Value" ""
			(at 0 0 0)
			(layer "B.Fab")
			(effects
				(font
					(size 1.27 1.27)
				)
				(justify mirror)
			)
		)
		(duplicate_pad_numbers_are_jumpers no)
		(fp_poly
			(pts
				(xy 0.2794 -0.1016) (xy -0.2794 -0.1016) (xy -0.2794 0.9906) (xy 0.2794 0.9906)
			)
			(stroke
				(width 0)
				(type default)
			)
			(fill no)
			(layer "B.CrtYd")
		)
		(fp_line
			(start -0.2794 -0.1016)
			(end 0.2794 -0.1016)
			(stroke
				(width 0.1)
				(type default)
			)
			(layer "B.Fab")
		)
		(fp_line
			(start -0.2794 0.9906)
			(end -0.2794 -0.1016)
			(stroke
				(width 0.1)
				(type default)
			)
			(layer "B.Fab")
		)
		(fp_line
			(start 0.2794 -0.1016)
			(end 0.2794 0.9906)
			(stroke
				(width 0.1)
				(type default)
			)
			(layer "B.Fab")
		)
		(fp_line
			(start 0.2794 0.9906)
			(end -0.2794 0.9906)
			(stroke
				(width 0.1)
				(type default)
			)
			(layer "B.Fab")
		)
		(pad "1" smd rect
			(at 0 0 180)
			(size 0.508 0.508)
			(layers "B.Cu" "B.Mask" "B.Paste")
			(net "FM_JTAG_PLD_EN_DEBUG")
		)
		(pad "2" smd rect
			(at 0 0.889 180)
			(size 0.508 0.508)
			(layers "B.Cu" "B.Mask" "B.Paste")
			(net "GND")
		)
		(zone
			(layer "B.Cu")
			(hatch none 0.5)
			(connect_pads
				(clearance 0)
			)
			(min_thickness 0.25)
			(keepout
				(tracks allowed)
				(vias not_allowed)
				(pads allowed)
				(copperpour not_allowed)
				(footprints allowed)
			)
			(placement
				(enabled no)
				(sheetname "")
			)
			(fill
				(thermal_gap 0.5)
				(thermal_bridge_width 0.5)
				(island_removal_mode 0)
			)
			(polygon
				(pts
					(xy 370.54409 -66.046604) (xy 370.03609 -66.046604) (xy 370.03609 -65.665604) (xy 370.54409 -65.665604)
				)
			)
		)
		(zone
			(layer "B.Cu")
			(hatch none 0.5)
			(connect_pads
				(clearance 0)
			)
			(min_thickness 0.25)
			(keepout
				(tracks not_allowed)
				(vias allowed)
				(pads allowed)
				(copperpour not_allowed)
				(footprints allowed)
			)
			(placement
				(enabled no)
				(sheetname "")
			)
			(fill
				(thermal_gap 0.5)
				(thermal_bridge_width 0.5)
				(island_removal_mode 0)
			)
			(polygon
				(pts
					(xy 370.54409 -65.665604) (xy 370.03609 -65.665604) (xy 370.03609 -66.046604) (xy 370.54409 -66.046604)
				)
			)
		)
	)
	(footprint ""
		(layer "B.Cu")
		(at 373.761 -6.1595)
		(property "Reference" "R7G31"
			(at 0 0 0)
			(layer "B.SilkS")
			(hide yes)
			(effects
				(font
					(size 1.27 1.27)
				)
				(justify mirror)
			)
		)
		(property "Value" ""
			(at 0 0 0)
			(layer "B.Fab")
			(effects
				(font
					(size 1.27 1.27)
				)
				(justify mirror)
			)
		)
		(duplicate_pad_numbers_are_jumpers no)
		(fp_poly
			(pts
				(xy 0.2794 -0.1016) (xy -0.2794 -0.1016) (xy -0.2794 0.9906) (xy 0.2794 0.9906)
			)
			(stroke
				(width 0)
				(type default)
			)
			(fill no)
			(layer "B.CrtYd")
		)
		(fp_line
			(start -0.2794 -0.1016)
			(end 0.2794 -0.1016)
			(stroke
				(width 0.1)
				(type default)
			)
			(layer "B.Fab")
		)
		(fp_line
			(start -0.2794 0.9906)
			(end -0.2794 -0.1016)
			(stroke
				(width 0.1)
				(type default)
			)
			(layer "B.Fab")
		)
		(fp_line
			(start 0.2794 -0.1016)
			(end 0.2794 0.9906)
			(stroke
				(width 0.1)
				(type default)
			)
			(layer "B.Fab")
		)
		(fp_line
			(start 0.2794 0.9906)
			(end -0.2794 0.9906)
			(stroke
				(width 0.1)
				(type default)
			)
			(layer "B.Fab")
		)
		(pad "1" smd rect
			(at 0 0 180)
			(size 0.508 0.508)
			(layers "B.Cu" "B.Mask" "B.Paste")
			(net "P3V3_STBY")
		)
		(pad "2" smd rect
			(at 0 0.889 180)
			(size 0.508 0.508)
			(layers "B.Cu" "B.Mask" "B.Paste")
			(net "PU_BIOS_RECOVER_BOOT")
		)
		(zone
			(layer "B.Cu")
			(hatch none 0.5)
			(connect_pads
				(clearance 0)
			)
			(min_thickness 0.25)
			(keepout
				(tracks allowed)
				(vias not_allowed)
				(pads allowed)
				(copperpour not_allowed)
				(footprints allowed)
			)
			(placement
				(enabled no)
				(sheetname "")
			)
			(fill
				(thermal_gap 0.5)
				(thermal_bridge_width 0.5)
				(island_removal_mode 0)
			)
			(polygon
				(pts
					(xy 374.015 -5.9055) (xy 373.507 -5.9055) (xy 373.507 -5.5245) (xy 374.015 -5.5245)
				)
			)
		)
		(zone
			(layer "B.Cu")
			(hatch none 0.5)
			(connect_pads
				(clearance 0)
			)
			(min_thickness 0.25)
			(keepout
				(tracks not_allowed)
				(vias allowed)
				(pads allowed)
				(copperpour not_allowed)
				(footprints allowed)
			)
			(placement
				(enabled no)
				(sheetname "")
			)
			(fill
				(thermal_gap 0.5)
				(thermal_bridge_width 0.5)
				(island_removal_mode 0)
			)
			(polygon
				(pts
					(xy 374.015 -5.5245) (xy 373.507 -5.5245) (xy 373.507 -5.9055) (xy 374.015 -5.9055)
				)
			)
		)
	)
	(footprint ""
		(layer "B.Cu")
		(at 210.847432 -57.023 -90)
		(property "Reference" "C6R9"
			(at -0.86233 -3.401568 0)
			(unlocked yes)
			(layer "B.SilkS")
			(effects
				(font
					(size 0.7874 0.5842)
					(thickness 0.1524)
				)
				(justify mirror)
			)
		)
		(property "Value" ""
			(at 0 0 90)
			(layer "B.Fab")
			(effects
				(font
					(size 1.27 1.27)
				)
				(justify mirror)
			)
		)
		(duplicate_pad_numbers_are_jumpers no)
		(fp_line
			(start -2.286 7.366)
			(end -1.600708 7.366)
			(stroke
				(width 0.1524)
				(type default)
			)
			(layer "B.SilkS")
		)
		(fp_line
			(start -2.286 7.366)
			(end -2.286 1.63195)
			(stroke
				(width 0.1524)
				(type default)
			)
			(layer "B.SilkS")
		)
		(fp_line
			(start 2.286 7.366)
			(end 1.60147 7.366)
			(stroke
				(width 0.1524)
				(type default)
			)
			(layer "B.SilkS")
		)
		(fp_line
			(start 2.286 7.366)
			(end 2.286 1.632712)
			(stroke
				(width 0.1524)
				(type default)
			)
			(layer "B.SilkS")
		)
		(fp_line
			(start -2.504948 1.633728)
			(end -1.6002 1.633728)
			(stroke
				(width 0.1524)
				(type default)
			)
			(layer "B.SilkS")
		)
		(fp_line
			(start 2.563114 1.633728)
			(end 1.6002 1.633728)
			(stroke
				(width 0.1524)
				(type default)
			)
			(layer "B.SilkS")
		)
		(fp_line
			(start -2.504948 -1.616456)
			(end -2.504948 1.633728)
			(stroke
				(width 0.1524)
				(type default)
			)
			(layer "B.SilkS")
		)
		(fp_line
			(start -1.6002 -1.616456)
			(end -2.504948 -1.616456)
			(stroke
				(width 0.1524)
				(type default)
			)
			(layer "B.SilkS")
		)
		(fp_line
			(start 1.6002 -1.616456)
			(end 2.563114 -1.616456)
			(stroke
				(width 0.1524)
				(type default)
			)
			(layer "B.SilkS")
		)
		(fp_line
			(start 2.563114 -1.616456)
			(end 2.563114 1.633728)
			(stroke
				(width 0.1524)
				(type default)
			)
			(layer "B.SilkS")
		)
		(fp_rect
			(start 2.286 7.366)
			(end -2.286 -0.254)
			(stroke
				(width 0)
				(type default)
			)
			(fill no)
			(layer "B.CrtYd")
		)
		(fp_line
			(start -2.286 7.366)
			(end 2.286 7.366)
			(stroke
				(width 0.1)
				(type default)
			)
			(layer "B.Fab")
		)
		(fp_line
			(start 2.286 7.366)
			(end 2.286 -0.254)
			(stroke
				(width 0.1)
				(type default)
			)
			(layer "B.Fab")
		)
		(fp_line
			(start -2.286 -0.254)
			(end -2.286 7.366)
			(stroke
				(width 0.1)
				(type default)
			)
			(layer "B.Fab")
		)
		(fp_line
			(start 2.286 -0.254)
			(end -2.286 -0.254)
			(stroke
				(width 0.1)
				(type default)
			)
			(layer "B.Fab")
		)
		(pad "1" smd rect
			(at 0 0 90)
			(size 2.54 3.048)
			(layers "B.Cu" "B.Mask" "B.Paste")
			(net "PVCCIN_CPU0")
		)
		(pad "2" smd rect
			(at 0 7.112 90)
			(size 2.54 3.048)
			(layers "B.Cu" "B.Mask" "B.Paste")
			(net "GND")
		)
	)
)
